(kicad_pcb
	(version 20260206)
	(generator "pcbnew")
	(generator_version "10.0")
	(general
		(thickness 1.6)
		(legacy_teardrops no)
	)
	(paper "A4")
	(title_block
		(title "04192023_DAF0TMB3IC0_F0TG_MB_C_brd_V02_OCP.brd")
		(comment 1 "Grand Teton / footprints 5516-5523 of 8354")
	)
	(layers
		(0 "F.Cu" signal "TOP")
		(4 "In1.Cu" signal "GND")
		(6 "In2.Cu" signal "IN1")
		(8 "In3.Cu" signal "GND1")
		(10 "In4.Cu" signal "IN2")
		(12 "In5.Cu" signal "GND2")
		(14 "In6.Cu" signal "IN3")
		(16 "In7.Cu" signal "GND3")
		(18 "In8.Cu" signal "VCC")
		(20 "In9.Cu" signal "VCC1")
		(22 "In10.Cu" signal "GND4")
		(24 "In11.Cu" signal "IN4")
		(26 "In12.Cu" signal "GND5")
		(28 "In13.Cu" signal "IN5")
		(30 "In14.Cu" signal "GND6")
		(32 "In15.Cu" signal "IN6")
		(34 "In16.Cu" signal "GND7")
		(2 "B.Cu" signal "BOTTOM")
		(9 "F.Adhes" user "F.Adhesive")
		(11 "B.Adhes" user "B.Adhesive")
		(13 "F.Paste" user "Package Geometry/Pastemask Top")
		(15 "B.Paste" user "Package Geometry/Pastemask Bottom")
		(5 "F.SilkS" user "Ref Des/Silkscreen Top")
		(7 "B.SilkS" user "Ref Des/Silkscreen Bottom")
		(1 "F.Mask" user "Board Geometry/Soldermask Top")
		(3 "B.Mask" user "Board Geometry/Soldermask Bottom")
		(17 "Dwgs.User" user "User.Drawings")
		(19 "Cmts.User" user "User.Comments")
		(21 "Eco1.User" user "User.Eco1")
		(23 "Eco2.User" user "User.Eco2")
		(25 "Edge.Cuts" user "Board Geometry/Outline")
		(27 "Margin" user)
		(31 "F.CrtYd" user "Package Geometry/Place Bound Top")
		(29 "B.CrtYd" user "Package Geometry/Place Bound Bottom")
		(35 "F.Fab" user "Ref Des/Assembly Top")
		(33 "B.Fab" user "Ref Des/Assembly Bottom")
	)
	(footprint ""
		(layer "B.Cu")
		(at 104.514904 -408.980894 180)
		(property "Reference" "C99"
			(at 0 0 0)
			(layer "B.SilkS")
			(hide yes)
			(effects
				(font
					(size 1.27 1.27)
				)
				(justify mirror)
			)
		)
		(property "Value" ""
			(at 0 0 0)
			(layer "B.Fab")
			(effects
				(font
					(size 1.27 1.27)
				)
				(justify mirror)
			)
		)
		(duplicate_pad_numbers_are_jumpers no)
		(fp_line
			(start 0.7874 0.4064)
			(end 0.7874 -0.4064)
			(stroke
				(width 0.1524)
				(type default)
			)
			(layer "B.SilkS")
		)
		(fp_line
			(start 0.7874 -0.4064)
			(end -0.7874 -0.4064)
			(stroke
				(width 0.1524)
				(type default)
			)
			(layer "B.SilkS")
		)
		(fp_line
			(start -0.7874 0.4064)
			(end 0.7874 0.4064)
			(stroke
				(width 0.1524)
				(type default)
			)
			(layer "B.SilkS")
		)
		(fp_line
			(start -0.7874 -0.4064)
			(end -0.7874 0.4064)
			(stroke
				(width 0.1524)
				(type default)
			)
			(layer "B.SilkS")
		)
		(fp_line
			(start 0.67945 0.3048)
			(end 0.67945 -0.305054)
			(stroke
				(width 0.1)
				(type default)
			)
			(layer "B.Fab")
		)
		(fp_line
			(start 0.67945 -0.305054)
			(end 0.12065 -0.305054)
			(stroke
				(width 0.1)
				(type default)
			)
			(layer "B.Fab")
		)
		(fp_line
			(start 0.12065 0.3048)
			(end 0.67945 0.3048)
			(stroke
				(width 0.1)
				(type default)
			)
			(layer "B.Fab")
		)
		(fp_line
			(start 0.12065 0.2794)
			(end 0.12065 0.3048)
			(stroke
				(width 0.1)
				(type default)
			)
			(layer "B.Fab")
		)
		(fp_line
			(start 0.12065 -0.2794)
			(end -0.12065 -0.2794)
			(stroke
				(width 0.1)
				(type default)
			)
			(layer "B.Fab")
		)
		(fp_line
			(start 0.12065 -0.305054)
			(end 0.12065 -0.2794)
			(stroke
				(width 0.1)
				(type default)
			)
			(layer "B.Fab")
		)
		(fp_line
			(start -0.120396 0.3048)
			(end -0.120396 0.2794)
			(stroke
				(width 0.1)
				(type default)
			)
			(layer "B.Fab")
		)
		(fp_line
			(start -0.120396 0.2794)
			(end 0.12065 0.2794)
			(stroke
				(width 0.1)
				(type default)
			)
			(layer "B.Fab")
		)
		(fp_line
			(start -0.12065 -0.2794)
			(end -0.12065 -0.3048)
			(stroke
				(width 0.1)
				(type default)
			)
			(layer "B.Fab")
		)
		(fp_line
			(start -0.12065 -0.3048)
			(end -0.67945 -0.3048)
			(stroke
				(width 0.1)
				(type default)
			)
			(layer "B.Fab")
		)
		(fp_line
			(start -0.67945 0.3048)
			(end -0.120396 0.3048)
			(stroke
				(width 0.1)
				(type default)
			)
			(layer "B.Fab")
		)
		(fp_line
			(start -0.67945 -0.3048)
			(end -0.67945 0.3048)
			(stroke
				(width 0.1)
				(type default)
			)
			(layer "B.Fab")
		)
		(pad "1" smd circle
			(at 0.40005 0)
			(size 0 0)
			(layers "B.Cu" "B.Mask" "B.Paste")
			(net "P3V3_9ZXL045_P1_VDD")
		)
		(pad "2" smd circle
			(at -0.40005 0)
			(size 0 0)
			(layers "B.Cu" "B.Mask" "B.Paste")
			(net "GND")
		)
	)
	(footprint ""
		(layer "B.Cu")
		(at 184.257696 -133.791452 90)
		(property "Reference" "R6805"
			(at 0 0 90)
			(layer "B.SilkS")
			(hide yes)
			(effects
				(font
					(size 1.27 1.27)
				)
				(justify mirror)
			)
		)
		(property "Value" ""
			(at 0 0 90)
			(layer "B.Fab")
			(effects
				(font
					(size 1.27 1.27)
				)
				(justify mirror)
			)
		)
		(duplicate_pad_numbers_are_jumpers no)
		(fp_line
			(start 0.7874 -0.4064)
			(end -0.7874 -0.4064)
			(stroke
				(width 0.1524)
				(type default)
			)
			(layer "B.SilkS")
		)
		(fp_line
			(start -0.7874 -0.4064)
			(end -0.7874 0.4064)
			(stroke
				(width 0.1524)
				(type default)
			)
			(layer "B.SilkS")
		)
		(fp_line
			(start 0.7874 0.4064)
			(end 0.7874 -0.4064)
			(stroke
				(width 0.1524)
				(type default)
			)
			(layer "B.SilkS")
		)
		(fp_line
			(start -0.7874 0.4064)
			(end 0.7874 0.4064)
			(stroke
				(width 0.1524)
				(type default)
			)
			(layer "B.SilkS")
		)
		(fp_line
			(start 0.67945 -0.305054)
			(end 0.12065 -0.305054)
			(stroke
				(width 0.1)
				(type default)
			)
			(layer "B.Fab")
		)
		(fp_line
			(start 0.12065 -0.305054)
			(end 0.12065 -0.2794)
			(stroke
				(width 0.1)
				(type default)
			)
			(layer "B.Fab")
		)
		(fp_line
			(start -0.12065 -0.3048)
			(end -0.67945 -0.3048)
			(stroke
				(width 0.1)
				(type default)
			)
			(layer "B.Fab")
		)
		(fp_line
			(start -0.67945 -0.3048)
			(end -0.67945 0.3048)
			(stroke
				(width 0.1)
				(type default)
			)
			(layer "B.Fab")
		)
		(fp_line
			(start 0.12065 -0.2794)
			(end -0.12065 -0.2794)
			(stroke
				(width 0.1)
				(type default)
			)
			(layer "B.Fab")
		)
		(fp_line
			(start -0.12065 -0.2794)
			(end -0.12065 -0.3048)
			(stroke
				(width 0.1)
				(type default)
			)
			(layer "B.Fab")
		)
		(fp_line
			(start 0.12065 0.2794)
			(end 0.12065 0.3048)
			(stroke
				(width 0.1)
				(type default)
			)
			(layer "B.Fab")
		)
		(fp_line
			(start -0.120396 0.2794)
			(end 0.12065 0.2794)
			(stroke
				(width 0.1)
				(type default)
			)
			(layer "B.Fab")
		)
		(fp_line
			(start 0.67945 0.3048)
			(end 0.67945 -0.305054)
			(stroke
				(width 0.1)
				(type default)
			)
			(layer "B.Fab")
		)
		(fp_line
			(start 0.12065 0.3048)
			(end 0.67945 0.3048)
			(stroke
				(width 0.1)
				(type default)
			)
			(layer "B.Fab")
		)
		(fp_line
			(start -0.120396 0.3048)
			(end -0.120396 0.2794)
			(stroke
				(width 0.1)
				(type default)
			)
			(layer "B.Fab")
		)
		(fp_line
			(start -0.67945 0.3048)
			(end -0.120396 0.3048)
			(stroke
				(width 0.1)
				(type default)
			)
			(layer "B.Fab")
		)
		(pad "1" smd circle
			(at 0.40005 0 270)
			(size 0 0)
			(layers "B.Cu" "B.Mask" "B.Paste")
			(net "RST_RT_CPU0_P0_RESET_R_N")
		)
		(pad "2" smd circle
			(at -0.40005 0 270)
			(size 0 0)
			(layers "B.Cu" "B.Mask" "B.Paste")
			(net "RST_RT_CPU0_P0_RESET_R2_N")
		)
	)
	(footprint ""
		(layer "B.Cu")
		(at 311.426606 -416.899344 90)
		(property "Reference" "C6538"
			(at 0 0 90)
			(layer "B.SilkS")
			(hide yes)
			(effects
				(font
					(size 1.27 1.27)
				)
				(justify mirror)
			)
		)
		(property "Value" ""
			(at 0 0 90)
			(layer "B.Fab")
			(effects
				(font
					(size 1.27 1.27)
				)
				(justify mirror)
			)
		)
		(duplicate_pad_numbers_are_jumpers no)
		(fp_line
			(start 0.299974 -0.150114)
			(end -0.299974 -0.150114)
			(stroke
				(width 0.1)
				(type default)
			)
			(layer "B.Fab")
		)
		(fp_line
			(start -0.299974 -0.150114)
			(end -0.299974 0.150114)
			(stroke
				(width 0.1)
				(type default)
			)
			(layer "B.Fab")
		)
		(fp_line
			(start 0.299974 0.150114)
			(end 0.299974 -0.150114)
			(stroke
				(width 0.1)
				(type default)
			)
			(layer "B.Fab")
		)
		(fp_line
			(start -0.299974 0.150114)
			(end 0.299974 0.150114)
			(stroke
				(width 0.1)
				(type default)
			)
			(layer "B.Fab")
		)
		(pad "1" smd rect
			(at 0.2667 0 270)
			(size 0.3048 0.381)
			(layers "B.Cu" "B.Mask" "B.Paste")
			(net "P5E_CPU0_P1_TX_BUF_C_DN<2>")
		)
		(pad "2" smd rect
			(at -0.2667 0 270)
			(size 0.3048 0.381)
			(layers "B.Cu" "B.Mask" "B.Paste")
			(net "P5E_CPU0_P1_TX_BUF_DN<2>")
		)
	)
	(footprint ""
		(layer "B.Cu")
		(at 165.599618 -416.946588 180)
		(property "Reference" "R4119"
			(at 0 0 0)
			(layer "B.SilkS")
			(hide yes)
			(effects
				(font
					(size 1.27 1.27)
				)
				(justify mirror)
			)
		)
		(property "Value" ""
			(at 0 0 0)
			(layer "B.Fab")
			(effects
				(font
					(size 1.27 1.27)
				)
				(justify mirror)
			)
		)
		(duplicate_pad_numbers_are_jumpers no)
		(fp_line
			(start 0.7874 0.4064)
			(end 0.7874 -0.4064)
			(stroke
				(width 0.1524)
				(type default)
			)
			(layer "B.SilkS")
		)
		(fp_line
			(start 0.7874 -0.4064)
			(end -0.7874 -0.4064)
			(stroke
				(width 0.1524)
				(type default)
			)
			(layer "B.SilkS")
		)
		(fp_line
			(start -0.7874 0.4064)
			(end 0.7874 0.4064)
			(stroke
				(width 0.1524)
				(type default)
			)
			(layer "B.SilkS")
		)
		(fp_line
			(start -0.7874 -0.4064)
			(end -0.7874 0.4064)
			(stroke
				(width 0.1524)
				(type default)
			)
			(layer "B.SilkS")
		)
		(fp_line
			(start 0.67945 0.3048)
			(end 0.67945 -0.305054)
			(stroke
				(width 0.1)
				(type default)
			)
			(layer "B.Fab")
		)
		(fp_line
			(start 0.67945 -0.305054)
			(end 0.12065 -0.305054)
			(stroke
				(width 0.1)
				(type default)
			)
			(layer "B.Fab")
		)
		(fp_line
			(start 0.12065 0.3048)
			(end 0.67945 0.3048)
			(stroke
				(width 0.1)
				(type default)
			)
			(layer "B.Fab")
		)
		(fp_line
			(start 0.12065 0.2794)
			(end 0.12065 0.3048)
			(stroke
				(width 0.1)
				(type default)
			)
			(layer "B.Fab")
		)
		(fp_line
			(start 0.12065 -0.2794)
			(end -0.12065 -0.2794)
			(stroke
				(width 0.1)
				(type default)
			)
			(layer "B.Fab")
		)
		(fp_line
			(start 0.12065 -0.305054)
			(end 0.12065 -0.2794)
			(stroke
				(width 0.1)
				(type default)
			)
			(layer "B.Fab")
		)
		(fp_line
			(start -0.120396 0.3048)
			(end -0.120396 0.2794)
			(stroke
				(width 0.1)
				(type default)
			)
			(layer "B.Fab")
		)
		(fp_line
			(start -0.120396 0.2794)
			(end 0.12065 0.2794)
			(stroke
				(width 0.1)
				(type default)
			)
			(layer "B.Fab")
		)
		(fp_line
			(start -0.12065 -0.2794)
			(end -0.12065 -0.3048)
			(stroke
				(width 0.1)
				(type default)
			)
			(layer "B.Fab")
		)
		(fp_line
			(start -0.12065 -0.3048)
			(end -0.67945 -0.3048)
			(stroke
				(width 0.1)
				(type default)
			)
			(layer "B.Fab")
		)
		(fp_line
			(start -0.67945 0.3048)
			(end -0.120396 0.3048)
			(stroke
				(width 0.1)
				(type default)
			)
			(layer "B.Fab")
		)
		(fp_line
			(start -0.67945 -0.3048)
			(end -0.67945 0.3048)
			(stroke
				(width 0.1)
				(type default)
			)
			(layer "B.Fab")
		)
		(pad "1" smd circle
			(at 0.40005 0)
			(size 0 0)
			(layers "B.Cu" "B.Mask" "B.Paste")
			(net "P3V3_AUX")
		)
		(pad "2" smd circle
			(at -0.40005 0)
			(size 0 0)
			(layers "B.Cu" "B.Mask" "B.Paste")
			(net "GPU_3V3IO_RSVD0_FFU")
		)
	)
	(footprint ""
		(layer "B.Cu")
		(at 128.653286 -408.517344 90)
		(property "Reference" "C6734"
			(at 0 0 90)
			(layer "B.SilkS")
			(hide yes)
			(effects
				(font
					(size 1.27 1.27)
				)
				(justify mirror)
			)
		)
		(property "Value" ""
			(at 0 0 90)
			(layer "B.Fab")
			(effects
				(font
					(size 1.27 1.27)
				)
				(justify mirror)
			)
		)
		(duplicate_pad_numbers_are_jumpers no)
		(fp_line
			(start 0.299974 -0.150114)
			(end -0.299974 -0.150114)
			(stroke
				(width 0.1)
				(type default)
			)
			(layer "B.Fab")
		)
		(fp_line
			(start -0.299974 -0.150114)
			(end -0.299974 0.150114)
			(stroke
				(width 0.1)
				(type default)
			)
			(layer "B.Fab")
		)
		(fp_line
			(start 0.299974 0.150114)
			(end 0.299974 -0.150114)
			(stroke
				(width 0.1)
				(type default)
			)
			(layer "B.Fab")
		)
		(fp_line
			(start -0.299974 0.150114)
			(end 0.299974 0.150114)
			(stroke
				(width 0.1)
				(type default)
			)
			(layer "B.Fab")
		)
		(pad "1" smd rect
			(at 0.2667 0 270)
			(size 0.3048 0.381)
			(layers "B.Cu" "B.Mask" "B.Paste")
			(net "P5E_CPU1_P3_TX_BUF_C_DN<4>")
		)
		(pad "2" smd rect
			(at -0.2667 0 270)
			(size 0.3048 0.381)
			(layers "B.Cu" "B.Mask" "B.Paste")
			(net "P5E_CPU1_P3_TX_BUF_DN<4>")
		)
	)
	(footprint ""
		(layer "B.Cu")
		(at 376.377962 -416.899344 90)
		(property "Reference" "C6599"
			(at 0 0 90)
			(layer "B.SilkS")
			(hide yes)
			(effects
				(font
					(size 1.27 1.27)
				)
				(justify mirror)
			)
		)
		(property "Value" ""
			(at 0 0 90)
			(layer "B.Fab")
			(effects
				(font
					(size 1.27 1.27)
				)
				(justify mirror)
			)
		)
		(duplicate_pad_numbers_are_jumpers no)
		(fp_line
			(start 0.299974 -0.150114)
			(end -0.299974 -0.150114)
			(stroke
				(width 0.1)
				(type default)
			)
			(layer "B.Fab")
		)
		(fp_line
			(start -0.299974 -0.150114)
			(end -0.299974 0.150114)
			(stroke
				(width 0.1)
				(type default)
			)
			(layer "B.Fab")
		)
		(fp_line
			(start 0.299974 0.150114)
			(end 0.299974 -0.150114)
			(stroke
				(width 0.1)
				(type default)
			)
			(layer "B.Fab")
		)
		(fp_line
			(start -0.299974 0.150114)
			(end 0.299974 0.150114)
			(stroke
				(width 0.1)
				(type default)
			)
			(layer "B.Fab")
		)
		(pad "1" smd rect
			(at 0.2667 0 270)
			(size 0.3048 0.381)
			(layers "B.Cu" "B.Mask" "B.Paste")
			(net "P5E_CPU0_P3_TX_BUF_C_DP<1>")
		)
		(pad "2" smd rect
			(at -0.2667 0 270)
			(size 0.3048 0.381)
			(layers "B.Cu" "B.Mask" "B.Paste")
			(net "P5E_CPU0_P3_TX_BUF_DP<1>")
		)
	)
	(footprint ""
		(layer "B.Cu")
		(at 54.578504 -386.766562 90)
		(property "Reference" "C134"
			(at 0 0 90)
			(layer "B.SilkS")
			(hide yes)
			(effects
				(font
					(size 1.27 1.27)
				)
				(justify mirror)
			)
		)
		(property "Value" ""
			(at 0 0 90)
			(layer "B.Fab")
			(effects
				(font
					(size 1.27 1.27)
				)
				(justify mirror)
			)
		)
		(duplicate_pad_numbers_are_jumpers no)
		(fp_line
			(start 0.299974 -0.150114)
			(end -0.299974 -0.150114)
			(stroke
				(width 0.1)
				(type default)
			)
			(layer "B.Fab")
		)
		(fp_line
			(start -0.299974 -0.150114)
			(end -0.299974 0.150114)
			(stroke
				(width 0.1)
				(type default)
			)
			(layer "B.Fab")
		)
		(fp_line
			(start 0.299974 0.150114)
			(end 0.299974 -0.150114)
			(stroke
				(width 0.1)
				(type default)
			)
			(layer "B.Fab")
		)
		(fp_line
			(start -0.299974 0.150114)
			(end 0.299974 0.150114)
			(stroke
				(width 0.1)
				(type default)
			)
			(layer "B.Fab")
		)
		(pad "1" smd rect
			(at 0.2667 0 270)
			(size 0.3048 0.381)
			(layers "B.Cu" "B.Mask" "B.Paste")
			(net "P1V8_CPU1_RT0_1A")
		)
		(pad "2" smd rect
			(at -0.2667 0 270)
			(size 0.3048 0.381)
			(layers "B.Cu" "B.Mask" "B.Paste")
			(net "GND")
		)
	)
	(footprint ""
		(layer "B.Cu")
		(at 349.421958 -245.487952 180)
		(property "Reference" "C2189"
			(at 0 0 0)
			(layer "B.SilkS")
			(hide yes)
			(effects
				(font
					(size 1.27 1.27)
				)
				(justify mirror)
			)
		)
		(property "Value" ""
			(at 0 0 0)
			(layer "B.Fab")
			(effects
				(font
					(size 1.27 1.27)
				)
				(justify mirror)
			)
		)
		(duplicate_pad_numbers_are_jumpers no)
		(fp_line
			(start 0.7874 0.4064)
			(end 0.7874 -0.4064)
			(stroke
				(width 0.1524)
				(type default)
			)
			(layer "B.SilkS")
		)
		(fp_line
			(start 0.7874 -0.4064)
			(end -0.7874 -0.4064)
			(stroke
				(width 0.1524)
				(type default)
			)
			(layer "B.SilkS")
		)
		(fp_line
			(start -0.7874 0.4064)
			(end 0.7874 0.4064)
			(stroke
				(width 0.1524)
				(type default)
			)
			(layer "B.SilkS")
		)
		(fp_line
			(start -0.7874 -0.4064)
			(end -0.7874 0.4064)
			(stroke
				(width 0.1524)
				(type default)
			)
			(layer "B.SilkS")
		)
		(fp_line
			(start 0.67945 0.3048)
			(end 0.67945 -0.305054)
			(stroke
				(width 0.1)
				(type default)
			)
			(layer "B.Fab")
		)
		(fp_line
			(start 0.67945 -0.305054)
			(end 0.12065 -0.305054)
			(stroke
				(width 0.1)
				(type default)
			)
			(layer "B.Fab")
		)
		(fp_line
			(start 0.12065 0.3048)
			(end 0.67945 0.3048)
			(stroke
				(width 0.1)
				(type default)
			)
			(layer "B.Fab")
		)
		(fp_line
			(start 0.12065 0.2794)
			(end 0.12065 0.3048)
			(stroke
				(width 0.1)
				(type default)
			)
			(layer "B.Fab")
		)
		(fp_line
			(start 0.12065 -0.2794)
			(end -0.12065 -0.2794)
			(stroke
				(width 0.1)
				(type default)
			)
			(layer "B.Fab")
		)
		(fp_line
			(start 0.12065 -0.305054)
			(end 0.12065 -0.2794)
			(stroke
				(width 0.1)
				(type default)
			)
			(layer "B.Fab")
		)
		(fp_line
			(start -0.120396 0.3048)
			(end -0.120396 0.2794)
			(stroke
				(width 0.1)
				(type default)
			)
			(layer "B.Fab")
		)
		(fp_line
			(start -0.120396 0.2794)
			(end 0.12065 0.2794)
			(stroke
				(width 0.1)
				(type default)
			)
			(layer "B.Fab")
		)
		(fp_line
			(start -0.12065 -0.2794)
			(end -0.12065 -0.3048)
			(stroke
				(width 0.1)
				(type default)
			)
			(layer "B.Fab")
		)
		(fp_line
			(start -0.12065 -0.3048)
			(end -0.67945 -0.3048)
			(stroke
				(width 0.1)
				(type default)
			)
			(layer "B.Fab")
		)
		(fp_line
			(start -0.67945 0.3048)
			(end -0.120396 0.3048)
			(stroke
				(width 0.1)
				(type default)
			)
			(layer "B.Fab")
		)
		(fp_line
			(start -0.67945 -0.3048)
			(end -0.67945 0.3048)
			(stroke
				(width 0.1)
				(type default)
			)
			(layer "B.Fab")
		)
		(pad "1" smd circle
			(at 0.40005 0)
			(size 0 0)
			(layers "B.Cu" "B.Mask" "B.Paste")
			(net "PVDDCR_CPU0_P0")
		)
		(pad "2" smd circle
			(at -0.40005 0)
			(size 0 0)
			(layers "B.Cu" "B.Mask" "B.Paste")
			(net "GND")
		)
	)
)
